(kicad_pcb
	(version 20260206)
	(generator "pcbnew")
	(generator_version "10.0")
	(general
		(thickness 1.6)
		(legacy_teardrops no)
	)
	(paper "A4")
	(title_block
		(title "baseboard — 13948-1b.1110WZS1818.brd")
		(comment 1 "Honey Badger (Wiwynn) / footprints 705-712 of 2523")
	)
	(layers
		(0 "F.Cu" signal "TOP")
		(4 "In1.Cu" signal "L2GND")
		(6 "In2.Cu" signal "L3")
		(8 "In3.Cu" signal "L4VCC")
		(10 "In4.Cu" signal "L5VCC")
		(12 "In5.Cu" signal "L6")
		(14 "In6.Cu" signal "L7GND")
		(2 "B.Cu" signal "BOTTOM")
		(9 "F.Adhes" user "F.Adhesive")
		(11 "B.Adhes" user "B.Adhesive")
		(13 "F.Paste" user "Package Geometry/Pastemask Top")
		(15 "B.Paste" user "Package Geometry/Pastemask Bottom")
		(5 "F.SilkS" user "Ref Des/Silkscreen Top")
		(7 "B.SilkS" user "Ref Des/Silkscreen Bottom")
		(1 "F.Mask" user "Board Geometry/Soldermask Top")
		(3 "B.Mask" user "Board Geometry/Soldermask Bottom")
		(17 "Dwgs.User" user "User.Drawings")
		(19 "Cmts.User" user "User.Comments")
		(21 "Eco1.User" user "User.Eco1")
		(23 "Eco2.User" user "User.Eco2")
		(25 "Edge.Cuts" user "Board Geometry/Outline")
		(27 "Margin" user)
		(31 "F.CrtYd" user "Package Geometry/Place Bound Top")
		(29 "B.CrtYd" user "Package Geometry/Place Bound Bottom")
		(35 "F.Fab" user "Ref Des/Assembly Top")
		(33 "B.Fab" user "Ref Des/Assembly Bottom")
	)
	(footprint ""
		(layer "F.Cu")
		(at 302.641 -160.274)
		(property "Reference" "TP91"
			(at 0 0 0)
			(layer "F.SilkS")
			(hide yes)
			(effects
				(font
					(size 1.27 1.27)
				)
			)
		)
		(property "Value" "TPAD28"
			(at 0.0127 -1.8034 0)
			(unlocked yes)
			(layer "F.Fab")
			(hide yes)
			(effects
				(font
					(size 1.016 1.016)
					(thickness 0.1524)
				)
			)
		)
		(property "Device Type" "TPAD28"
			(at 0.0127 -3.3274 0)
			(unlocked yes)
			(layer "F.Fab")
			(hide yes)
			(effects
				(font
					(size 1.016 1.016)
					(thickness 0.1524)
				)
			)
		)
		(duplicate_pad_numbers_are_jumpers no)
		(fp_poly
			(pts
				(arc
					(start 0.3556 0)
					(mid -0.3556 0)
					(end 0.3556 0)
				)
			)
			(stroke
				(width 0)
				(type default)
			)
			(fill no)
			(layer "F.CrtYd")
		)
		(fp_poly
			(pts
				(arc
					(start 0.6096 0)
					(mid -0.6096 0)
					(end 0.6096 0)
				)
			)
			(stroke
				(width 0)
				(type default)
			)
			(fill no)
			(layer "F.Fab")
		)
		(pad "1" smd circle
			(at 0 0)
			(size 0.7112 0.7112)
			(layers "F.Cu" "F.Mask" "F.Paste")
			(net "TP_GPIOH2")
		)
	)
	(footprint ""
		(layer "F.Cu")
		(at 81.024222 -115.410742 -90)
		(property "Reference" "SR754"
			(at 0 0 270)
			(layer "F.SilkS")
			(hide yes)
			(effects
				(font
					(size 1.27 1.27)
				)
			)
		)
		(property "Value" "200KR2F-L-GP"
			(at 0.064008 -3.993896 270)
			(unlocked yes)
			(layer "F.Fab")
			(hide yes)
			(effects
				(font
					(size 1.016 1.016)
					(thickness 0.1524)
				)
			)
		)
		(property "Device Type" "R402H16"
			(at 0.064008 -5.517896 270)
			(unlocked yes)
			(layer "F.Fab")
			(hide yes)
			(effects
				(font
					(size 1.016 1.016)
					(thickness 0.1524)
				)
			)
		)
		(duplicate_pad_numbers_are_jumpers no)
		(fp_line
			(start -0.508 -0.9398)
			(end -0.508 0.9398)
			(stroke
				(width 0.1524)
				(type default)
			)
			(layer "F.SilkS")
		)
		(fp_line
			(start 0.508 -0.9398)
			(end -0.508 -0.9398)
			(stroke
				(width 0.1524)
				(type default)
			)
			(layer "F.SilkS")
		)
		(fp_rect
			(start -0.508 0.9398)
			(end 0.508 -0.9398)
			(stroke
				(width 0)
				(type default)
			)
			(fill no)
			(layer "F.CrtYd")
		)
		(fp_rect
			(start -0.508 0.9398)
			(end 0.508 -0.9398)
			(stroke
				(width 0)
				(type default)
			)
			(fill no)
			(layer "F.Fab")
		)
		(pad "1" smd custom
			(at 0 -0.4445 270)
			(size 0.1397 0.1397)
			(layers "F.Cu" "F.Mask" "F.Paste")
			(net "EXP_I2C_VREF_1")
			(options
				(clearance outline)
				(anchor circle)
			)
			(primitives
				(gr_poly
					(pts
						(arc
							(start -0.1778 -0.2794)
							(mid -0.249642 -0.249642)
							(end -0.2794 -0.1778)
						)
						(arc
							(start -0.2794 0.1778)
							(mid -0.249642 0.249642)
							(end -0.1778 0.2794)
						)
						(arc
							(start 0.1778 0.2794)
							(mid 0.249642 0.249642)
							(end 0.2794 0.1778)
						)
						(arc
							(start 0.2794 -0.1778)
							(mid 0.249642 -0.249642)
							(end 0.1778 -0.2794)
						)
					)
					(width 0)
					(fill yes)
				)
			)
		)
		(pad "2" smd custom
			(at 0 0.4445 270)
			(size 0.1397 0.1397)
			(layers "F.Cu" "F.Mask" "F.Paste")
			(net "P3V3_STBY")
			(options
				(clearance outline)
				(anchor circle)
			)
			(primitives
				(gr_poly
					(pts
						(arc
							(start -0.1778 -0.2794)
							(mid -0.249642 -0.249642)
							(end -0.2794 -0.1778)
						)
						(arc
							(start -0.2794 0.1778)
							(mid -0.249642 0.249642)
							(end -0.1778 0.2794)
						)
						(arc
							(start 0.1778 0.2794)
							(mid 0.249642 0.249642)
							(end 0.2794 0.1778)
						)
						(arc
							(start 0.2794 -0.1778)
							(mid 0.249642 -0.249642)
							(end 0.1778 -0.2794)
						)
					)
					(width 0)
					(fill yes)
				)
			)
		)
	)
	(footprint ""
		(layer "F.Cu")
		(at 107.45597 -75.057)
		(property "Reference" "R178"
			(at 0 0 0)
			(layer "F.SilkS")
			(hide yes)
			(effects
				(font
					(size 1.27 1.27)
				)
			)
		)
		(property "Value" "4K7R2F-GP"
			(at 0.064008 -3.993896 0)
			(unlocked yes)
			(layer "F.Fab")
			(hide yes)
			(effects
				(font
					(size 1.016 1.016)
					(thickness 0.1524)
				)
			)
		)
		(property "Device Type" "R402H16"
			(at 0.064008 -5.517896 0)
			(unlocked yes)
			(layer "F.Fab")
			(hide yes)
			(effects
				(font
					(size 1.016 1.016)
					(thickness 0.1524)
				)
			)
		)
		(duplicate_pad_numbers_are_jumpers no)
		(fp_line
			(start -0.508 -0.9398)
			(end -0.508 0.9398)
			(stroke
				(width 0.1524)
				(type default)
			)
			(layer "F.SilkS")
		)
		(fp_line
			(start 0.508 -0.9398)
			(end -0.508 -0.9398)
			(stroke
				(width 0.1524)
				(type default)
			)
			(layer "F.SilkS")
		)
		(fp_rect
			(start -0.508 0.9398)
			(end 0.508 -0.9398)
			(stroke
				(width 0)
				(type default)
			)
			(fill no)
			(layer "F.CrtYd")
		)
		(fp_rect
			(start -0.508 0.9398)
			(end 0.508 -0.9398)
			(stroke
				(width 0)
				(type default)
			)
			(fill no)
			(layer "F.Fab")
		)
		(pad "1" smd custom
			(at 0 -0.4445)
			(size 0.1397 0.1397)
			(layers "F.Cu" "F.Mask" "F.Paste")
			(net "P3V3_STBY")
			(options
				(clearance outline)
				(anchor circle)
			)
			(primitives
				(gr_poly
					(pts
						(arc
							(start -0.1778 -0.2794)
							(mid -0.249642 -0.249642)
							(end -0.2794 -0.1778)
						)
						(arc
							(start -0.2794 0.1778)
							(mid -0.249642 0.249642)
							(end -0.1778 0.2794)
						)
						(arc
							(start 0.1778 0.2794)
							(mid 0.249642 0.249642)
							(end 0.2794 0.1778)
						)
						(arc
							(start 0.2794 -0.1778)
							(mid 0.249642 -0.249642)
							(end 0.1778 -0.2794)
						)
					)
					(width 0)
					(fill yes)
				)
			)
		)
		(pad "2" smd custom
			(at 0 0.4445)
			(size 0.1397 0.1397)
			(layers "F.Cu" "F.Mask" "F.Paste")
			(net "TEMP_4_A2")
			(options
				(clearance outline)
				(anchor circle)
			)
			(primitives
				(gr_poly
					(pts
						(arc
							(start -0.1778 -0.2794)
							(mid -0.249642 -0.249642)
							(end -0.2794 -0.1778)
						)
						(arc
							(start -0.2794 0.1778)
							(mid -0.249642 0.249642)
							(end -0.1778 0.2794)
						)
						(arc
							(start 0.1778 0.2794)
							(mid 0.249642 0.249642)
							(end 0.2794 0.1778)
						)
						(arc
							(start 0.2794 -0.1778)
							(mid 0.249642 -0.249642)
							(end 0.1778 -0.2794)
						)
					)
					(width 0)
					(fill yes)
				)
			)
		)
	)
	(footprint ""
		(layer "F.Cu")
		(at 316.484 -69.215 -90)
		(property "Reference" "R272"
			(at 0 0 270)
			(layer "F.SilkS")
			(hide yes)
			(effects
				(font
					(size 1.27 1.27)
				)
			)
		)
		(property "Value" "0R2J-2-GP"
			(at 0.064008 -3.993896 270)
			(unlocked yes)
			(layer "F.Fab")
			(hide yes)
			(effects
				(font
					(size 1.016 1.016)
					(thickness 0.1524)
				)
			)
		)
		(property "Device Type" "R402H16"
			(at 0.064008 -5.517896 270)
			(unlocked yes)
			(layer "F.Fab")
			(hide yes)
			(effects
				(font
					(size 1.016 1.016)
					(thickness 0.1524)
				)
			)
		)
		(duplicate_pad_numbers_are_jumpers no)
		(fp_line
			(start -0.508 -0.9398)
			(end -0.508 0.9398)
			(stroke
				(width 0.1524)
				(type default)
			)
			(layer "F.SilkS")
		)
		(fp_line
			(start 0.508 -0.9398)
			(end -0.508 -0.9398)
			(stroke
				(width 0.1524)
				(type default)
			)
			(layer "F.SilkS")
		)
		(fp_rect
			(start -0.508 0.9398)
			(end 0.508 -0.9398)
			(stroke
				(width 0)
				(type default)
			)
			(fill no)
			(layer "F.CrtYd")
		)
		(fp_rect
			(start -0.508 0.9398)
			(end 0.508 -0.9398)
			(stroke
				(width 0)
				(type default)
			)
			(fill no)
			(layer "F.Fab")
		)
		(pad "1" smd custom
			(at 0 -0.4445 270)
			(size 0.1397 0.1397)
			(layers "F.Cu" "F.Mask" "F.Paste")
			(net "CLK_100M_CLKBUFF_ENET2_DN")
			(options
				(clearance outline)
				(anchor circle)
			)
			(primitives
				(gr_poly
					(pts
						(arc
							(start -0.1778 -0.2794)
							(mid -0.249642 -0.249642)
							(end -0.2794 -0.1778)
						)
						(arc
							(start -0.2794 0.1778)
							(mid -0.249642 0.249642)
							(end -0.1778 0.2794)
						)
						(arc
							(start 0.1778 0.2794)
							(mid 0.249642 0.249642)
							(end 0.2794 0.1778)
						)
						(arc
							(start 0.2794 -0.1778)
							(mid 0.249642 -0.249642)
							(end 0.1778 -0.2794)
						)
					)
					(width 0)
					(fill yes)
				)
			)
		)
		(pad "2" smd custom
			(at 0 0.4445 270)
			(size 0.1397 0.1397)
			(layers "F.Cu" "F.Mask" "F.Paste")
			(net "PCIE_10G_REFCLK_2_N")
			(options
				(clearance outline)
				(anchor circle)
			)
			(primitives
				(gr_poly
					(pts
						(arc
							(start -0.1778 -0.2794)
							(mid -0.249642 -0.249642)
							(end -0.2794 -0.1778)
						)
						(arc
							(start -0.2794 0.1778)
							(mid -0.249642 0.249642)
							(end -0.1778 0.2794)
						)
						(arc
							(start 0.1778 0.2794)
							(mid 0.249642 0.249642)
							(end 0.2794 0.1778)
						)
						(arc
							(start 0.2794 -0.1778)
							(mid 0.249642 -0.249642)
							(end 0.1778 -0.2794)
						)
					)
					(width 0)
					(fill yes)
				)
			)
		)
	)
	(footprint ""
		(layer "F.Cu")
		(at 210.57997 -69.088 180)
		(property "Reference" "R19"
			(at 0 0 180)
			(layer "F.SilkS")
			(hide yes)
			(effects
				(font
					(size 1.27 1.27)
				)
			)
		)
		(property "Value" "0R2J-2-GP"
			(at 0.064008 -3.993896 180)
			(unlocked yes)
			(layer "F.Fab")
			(hide yes)
			(effects
				(font
					(size 1.016 1.016)
					(thickness 0.1524)
				)
			)
		)
		(property "Device Type" "R402H16"
			(at 0.064008 -5.517896 180)
			(unlocked yes)
			(layer "F.Fab")
			(hide yes)
			(effects
				(font
					(size 1.016 1.016)
					(thickness 0.1524)
				)
			)
		)
		(duplicate_pad_numbers_are_jumpers no)
		(fp_line
			(start 0.508 -0.9398)
			(end -0.508 -0.9398)
			(stroke
				(width 0.1524)
				(type default)
			)
			(layer "F.SilkS")
		)
		(fp_line
			(start -0.508 -0.9398)
			(end -0.508 0.9398)
			(stroke
				(width 0.1524)
				(type default)
			)
			(layer "F.SilkS")
		)
		(fp_rect
			(start -0.508 0.9398)
			(end 0.508 -0.9398)
			(stroke
				(width 0)
				(type default)
			)
			(fill no)
			(layer "F.CrtYd")
		)
		(fp_rect
			(start -0.508 0.9398)
			(end 0.508 -0.9398)
			(stroke
				(width 0)
				(type default)
			)
			(fill no)
			(layer "F.Fab")
		)
		(pad "1" smd custom
			(at 0 -0.4445 180)
			(size 0.1397 0.1397)
			(layers "F.Cu" "F.Mask" "F.Paste")
			(net "CPU_RESET_N")
			(options
				(clearance outline)
				(anchor circle)
			)
			(primitives
				(gr_poly
					(pts
						(arc
							(start -0.1778 -0.2794)
							(mid -0.249642 -0.249642)
							(end -0.2794 -0.1778)
						)
						(arc
							(start -0.2794 0.1778)
							(mid -0.249642 0.249642)
							(end -0.1778 0.2794)
						)
						(arc
							(start 0.1778 0.2794)
							(mid 0.249642 0.249642)
							(end 0.2794 0.1778)
						)
						(arc
							(start 0.2794 -0.1778)
							(mid 0.249642 -0.249642)
							(end 0.1778 -0.2794)
						)
					)
					(width 0)
					(fill yes)
				)
			)
		)
		(pad "2" smd custom
			(at 0 0.4445 180)
			(size 0.1397 0.1397)
			(layers "F.Cu" "F.Mask" "F.Paste")
			(net "CPU_RESET_N_R")
			(options
				(clearance outline)
				(anchor circle)
			)
			(primitives
				(gr_poly
					(pts
						(arc
							(start -0.1778 -0.2794)
							(mid -0.249642 -0.249642)
							(end -0.2794 -0.1778)
						)
						(arc
							(start -0.2794 0.1778)
							(mid -0.249642 0.249642)
							(end -0.1778 0.2794)
						)
						(arc
							(start 0.1778 0.2794)
							(mid 0.249642 0.249642)
							(end 0.2794 0.1778)
						)
						(arc
							(start 0.2794 -0.1778)
							(mid 0.249642 -0.249642)
							(end 0.1778 -0.2794)
						)
					)
					(width 0)
					(fill yes)
				)
			)
		)
	)
	(footprint ""
		(layer "F.Cu")
		(at 270.637 -41.021)
		(property "Reference" "PC45"
			(at 0 0 0)
			(layer "F.SilkS")
			(hide yes)
			(effects
				(font
					(size 1.27 1.27)
				)
			)
		)
		(property "Value" "SCD1U25V3KX-GP"
			(at 0 -2.8194 0)
			(unlocked yes)
			(layer "F.Fab")
			(hide yes)
			(effects
				(font
					(size 1.016 1.016)
					(thickness 0.1524)
				)
			)
		)
		(property "Device Type" "C603H36"
			(at 0 -4.3434 0)
			(unlocked yes)
			(layer "F.Fab")
			(hide yes)
			(effects
				(font
					(size 1.016 1.016)
					(thickness 0.1524)
				)
			)
		)
		(duplicate_pad_numbers_are_jumpers no)
		(fp_line
			(start 0.508 0)
			(end -0.508 0)
			(stroke
				(width 0.2032)
				(type default)
			)
			(layer "F.SilkS")
		)
		(fp_rect
			(start -0.5842 1.3335)
			(end 0.5842 -1.3335)
			(stroke
				(width 0)
				(type default)
			)
			(fill no)
			(layer "F.CrtYd")
		)
		(fp_rect
			(start -0.5842 1.3335)
			(end 0.5842 -1.3335)
			(stroke
				(width 0)
				(type default)
			)
			(fill no)
			(layer "F.Fab")
		)
		(pad "1" smd custom
			(at 0 -0.762)
			(size 0.2159 0.2159)
			(layers "F.Cu" "F.Mask" "F.Paste")
			(net "P1V8_STBY_VIN")
			(options
				(clearance outline)
				(anchor circle)
			)
			(primitives
				(gr_poly
					(pts
						(arc
							(start -0.3302 -0.4318)
							(mid -0.402042 -0.402042)
							(end -0.4318 -0.3302)
						)
						(arc
							(start -0.4318 0.3302)
							(mid -0.402042 0.402042)
							(end -0.3302 0.4318)
						)
						(arc
							(start 0.3302 0.4318)
							(mid 0.402042 0.402042)
							(end 0.4318 0.3302)
						)
						(arc
							(start 0.4318 -0.3302)
							(mid 0.402042 -0.402042)
							(end 0.3302 -0.4318)
						)
					)
					(width 0)
					(fill yes)
				)
			)
		)
		(pad "2" smd custom
			(at 0 0.762)
			(size 0.2159 0.2159)
			(layers "F.Cu" "F.Mask" "F.Paste")
			(net "GND")
			(options
				(clearance outline)
				(anchor circle)
			)
			(primitives
				(gr_poly
					(pts
						(arc
							(start -0.3302 -0.4318)
							(mid -0.402042 -0.402042)
							(end -0.4318 -0.3302)
						)
						(arc
							(start -0.4318 0.3302)
							(mid -0.402042 0.402042)
							(end -0.3302 0.4318)
						)
						(arc
							(start 0.3302 0.4318)
							(mid 0.402042 0.402042)
							(end 0.4318 0.3302)
						)
						(arc
							(start 0.4318 -0.3302)
							(mid 0.402042 -0.402042)
							(end 0.3302 -0.4318)
						)
					)
					(width 0)
					(fill yes)
				)
			)
		)
	)
	(footprint ""
		(layer "F.Cu")
		(at 180.648864 -22.551136 180)
		(property "Reference" "R387"
			(at 0 0 180)
			(layer "F.SilkS")
			(hide yes)
			(effects
				(font
					(size 1.27 1.27)
				)
			)
		)
		(property "Value" "4K7R2J-2-GP"
			(at 0.064008 -3.993896 180)
			(unlocked yes)
			(layer "F.Fab")
			(hide yes)
			(effects
				(font
					(size 1.016 1.016)
					(thickness 0.1524)
				)
			)
		)
		(property "Device Type" "R402H16"
			(at 0.064008 -5.517896 180)
			(unlocked yes)
			(layer "F.Fab")
			(hide yes)
			(effects
				(font
					(size 1.016 1.016)
					(thickness 0.1524)
				)
			)
		)
		(duplicate_pad_numbers_are_jumpers no)
		(fp_line
			(start 0.508 -0.9398)
			(end -0.508 -0.9398)
			(stroke
				(width 0.1524)
				(type default)
			)
			(layer "F.SilkS")
		)
		(fp_line
			(start -0.508 -0.9398)
			(end -0.508 0.9398)
			(stroke
				(width 0.1524)
				(type default)
			)
			(layer "F.SilkS")
		)
		(fp_rect
			(start -0.508 0.9398)
			(end 0.508 -0.9398)
			(stroke
				(width 0)
				(type default)
			)
			(fill no)
			(layer "F.CrtYd")
		)
		(fp_rect
			(start -0.508 0.9398)
			(end 0.508 -0.9398)
			(stroke
				(width 0)
				(type default)
			)
			(fill no)
			(layer "F.Fab")
		)
		(pad "1" smd custom
			(at 0 -0.4445 180)
			(size 0.1397 0.1397)
			(layers "F.Cu" "F.Mask" "F.Paste")
			(net "P3V3_STBY")
			(options
				(clearance outline)
				(anchor circle)
			)
			(primitives
				(gr_poly
					(pts
						(arc
							(start -0.1778 -0.2794)
							(mid -0.249642 -0.249642)
							(end -0.2794 -0.1778)
						)
						(arc
							(start -0.2794 0.1778)
							(mid -0.249642 0.249642)
							(end -0.1778 0.2794)
						)
						(arc
							(start 0.1778 0.2794)
							(mid 0.249642 0.249642)
							(end 0.2794 0.1778)
						)
						(arc
							(start 0.2794 -0.1778)
							(mid 0.249642 -0.249642)
							(end 0.1778 -0.2794)
						)
					)
					(width 0)
					(fill yes)
				)
			)
		)
		(pad "2" smd custom
			(at 0 0.4445 180)
			(size 0.1397 0.1397)
			(layers "F.Cu" "F.Mask" "F.Paste")
			(net "PHY_ANEN")
			(options
				(clearance outline)
				(anchor circle)
			)
			(primitives
				(gr_poly
					(pts
						(arc
							(start -0.1778 -0.2794)
							(mid -0.249642 -0.249642)
							(end -0.2794 -0.1778)
						)
						(arc
							(start -0.2794 0.1778)
							(mid -0.249642 0.249642)
							(end -0.1778 0.2794)
						)
						(arc
							(start 0.1778 0.2794)
							(mid 0.249642 0.249642)
							(end 0.2794 0.1778)
						)
						(arc
							(start 0.2794 -0.1778)
							(mid 0.249642 -0.249642)
							(end 0.1778 -0.2794)
						)
					)
					(width 0)
					(fill yes)
				)
			)
		)
	)
	(footprint ""
		(layer "F.Cu")
		(at 26.112216 -214.43188 -90)
		(property "Reference" "SR270"
			(at 0 0 270)
			(layer "F.SilkS")
			(hide yes)
			(effects
				(font
					(size 1.27 1.27)
				)
			)
		)
		(property "Value" "4K7R2F-GP"
			(at 0.064008 -3.993896 270)
			(unlocked yes)
			(layer "F.Fab")
			(hide yes)
			(effects
				(font
					(size 1.016 1.016)
					(thickness 0.1524)
				)
			)
		)
		(property "Device Type" "R402H16"
			(at 0.064008 -5.517896 270)
			(unlocked yes)
			(layer "F.Fab")
			(hide yes)
			(effects
				(font
					(size 1.016 1.016)
					(thickness 0.1524)
				)
			)
		)
		(duplicate_pad_numbers_are_jumpers no)
		(fp_line
			(start -0.508 -0.9398)
			(end -0.508 0.9398)
			(stroke
				(width 0.1524)
				(type default)
			)
			(layer "F.SilkS")
		)
		(fp_line
			(start 0.508 -0.9398)
			(end -0.508 -0.9398)
			(stroke
				(width 0.1524)
				(type default)
			)
			(layer "F.SilkS")
		)
		(fp_rect
			(start -0.508 0.9398)
			(end 0.508 -0.9398)
			(stroke
				(width 0)
				(type default)
			)
			(fill no)
			(layer "F.CrtYd")
		)
		(fp_rect
			(start -0.508 0.9398)
			(end 0.508 -0.9398)
			(stroke
				(width 0)
				(type default)
			)
			(fill no)
			(layer "F.Fab")
		)
		(pad "1" smd custom
			(at 0 -0.4445 270)
			(size 0.1397 0.1397)
			(layers "F.Cu" "F.Mask" "F.Paste")
			(net "P1V8_E")
			(options
				(clearance outline)
				(anchor circle)
			)
			(primitives
				(gr_poly
					(pts
						(arc
							(start -0.1778 -0.2794)
							(mid -0.249642 -0.249642)
							(end -0.2794 -0.1778)
						)
						(arc
							(start -0.2794 0.1778)
							(mid -0.249642 0.249642)
							(end -0.1778 0.2794)
						)
						(arc
							(start 0.1778 0.2794)
							(mid 0.249642 0.249642)
							(end 0.2794 0.1778)
						)
						(arc
							(start 0.2794 -0.1778)
							(mid 0.249642 -0.249642)
							(end 0.1778 -0.2794)
						)
					)
					(width 0)
					(fill yes)
				)
			)
		)
		(pad "2" smd custom
			(at 0 0.4445 270)
			(size 0.1397 0.1397)
			(layers "F.Cu" "F.Mask" "F.Paste")
			(net "HDD_PWR_IO_INT_N")
			(options
				(clearance outline)
				(anchor circle)
			)
			(primitives
				(gr_poly
					(pts
						(arc
							(start -0.1778 -0.2794)
							(mid -0.249642 -0.249642)
							(end -0.2794 -0.1778)
						)
						(arc
							(start -0.2794 0.1778)
							(mid -0.249642 0.249642)
							(end -0.1778 0.2794)
						)
						(arc
							(start 0.1778 0.2794)
							(mid 0.249642 0.249642)
							(end 0.2794 0.1778)
						)
						(arc
							(start 0.2794 -0.1778)
							(mid 0.249642 -0.249642)
							(end 0.1778 -0.2794)
						)
					)
					(width 0)
					(fill yes)
				)
			)
		)
	)
)
